(kicad_pcb
	(version 20260206)
	(generator "pcbnew")
	(generator_version "10.0")
	(general
		(thickness 1.6)
		(legacy_teardrops no)
	)
	(paper "A4")
	(title_block
		(title "baseboard — 13948-1b.1110WZS1818.brd")
		(comment 1 "Honey Badger (Wiwynn) / footprints 2284-2292 of 2523")
	)
	(layers
		(0 "F.Cu" signal "TOP")
		(4 "In1.Cu" signal "L2GND")
		(6 "In2.Cu" signal "L3")
		(8 "In3.Cu" signal "L4VCC")
		(10 "In4.Cu" signal "L5VCC")
		(12 "In5.Cu" signal "L6")
		(14 "In6.Cu" signal "L7GND")
		(2 "B.Cu" signal "BOTTOM")
		(9 "F.Adhes" user "F.Adhesive")
		(11 "B.Adhes" user "B.Adhesive")
		(13 "F.Paste" user "Package Geometry/Pastemask Top")
		(15 "B.Paste" user "Package Geometry/Pastemask Bottom")
		(5 "F.SilkS" user "Ref Des/Silkscreen Top")
		(7 "B.SilkS" user "Ref Des/Silkscreen Bottom")
		(1 "F.Mask" user "Board Geometry/Soldermask Top")
		(3 "B.Mask" user "Board Geometry/Soldermask Bottom")
		(17 "Dwgs.User" user "User.Drawings")
		(19 "Cmts.User" user "User.Comments")
		(21 "Eco1.User" user "User.Eco1")
		(23 "Eco2.User" user "User.Eco2")
		(25 "Edge.Cuts" user "Board Geometry/Outline")
		(27 "Margin" user)
		(31 "F.CrtYd" user "Package Geometry/Place Bound Top")
		(29 "B.CrtYd" user "Package Geometry/Place Bound Bottom")
		(35 "F.Fab" user "Ref Des/Assembly Top")
		(33 "B.Fab" user "Ref Des/Assembly Bottom")
	)
	(footprint ""
		(layer "B.Cu")
		(at 169.672 -113.284 90)
		(property "Reference" "PC185"
			(at 0 0 90)
			(layer "B.SilkS")
			(hide yes)
			(effects
				(font
					(size 1.27 1.27)
				)
				(justify mirror)
			)
		)
		(property "Value" "SCD1U50V3KX-GP"
			(at 0 -2.8194 90)
			(unlocked yes)
			(layer "B.Fab")
			(hide yes)
			(effects
				(font
					(size 1.016 1.016)
					(thickness 0.1524)
				)
				(justify mirror)
			)
		)
		(property "Device Type" "C603H36"
			(at 0 -4.3434 90)
			(unlocked yes)
			(layer "B.Fab")
			(hide yes)
			(effects
				(font
					(size 1.016 1.016)
					(thickness 0.1524)
				)
				(justify mirror)
			)
		)
		(duplicate_pad_numbers_are_jumpers no)
		(fp_line
			(start -0.508 0)
			(end 0.508 0)
			(stroke
				(width 0.2032)
				(type default)
			)
			(layer "B.SilkS")
		)
		(fp_rect
			(start 0.5842 1.3335)
			(end -0.5842 -1.3335)
			(stroke
				(width 0)
				(type default)
			)
			(fill no)
			(layer "B.CrtYd")
		)
		(fp_rect
			(start 0.5842 1.3335)
			(end -0.5842 -1.3335)
			(stroke
				(width 0)
				(type default)
			)
			(fill no)
			(layer "B.Fab")
		)
		(pad "1" smd custom
			(at 0 -0.762 270)
			(size 0.2159 0.2159)
			(layers "B.Cu" "B.Mask" "B.Paste")
			(net "P0V9_E_VBST")
			(options
				(clearance outline)
				(anchor circle)
			)
			(primitives
				(gr_poly
					(pts
						(arc
							(start -0.3302 0.4318)
							(mid -0.402042 0.402042)
							(end -0.4318 0.3302)
						)
						(arc
							(start -0.4318 -0.3302)
							(mid -0.402042 -0.402042)
							(end -0.3302 -0.4318)
						)
						(arc
							(start 0.3302 -0.4318)
							(mid 0.402042 -0.402042)
							(end 0.4318 -0.3302)
						)
						(arc
							(start 0.4318 0.3302)
							(mid 0.402042 0.402042)
							(end 0.3302 0.4318)
						)
					)
					(width 0)
					(fill yes)
				)
			)
		)
		(pad "2" smd custom
			(at 0 0.762 270)
			(size 0.2159 0.2159)
			(layers "B.Cu" "B.Mask" "B.Paste")
			(net "P0V9_E_VBST_RC")
			(options
				(clearance outline)
				(anchor circle)
			)
			(primitives
				(gr_poly
					(pts
						(arc
							(start -0.3302 0.4318)
							(mid -0.402042 0.402042)
							(end -0.4318 0.3302)
						)
						(arc
							(start -0.4318 -0.3302)
							(mid -0.402042 -0.402042)
							(end -0.3302 -0.4318)
						)
						(arc
							(start 0.3302 -0.4318)
							(mid 0.402042 -0.402042)
							(end 0.4318 -0.3302)
						)
						(arc
							(start 0.4318 0.3302)
							(mid 0.402042 0.402042)
							(end 0.3302 0.4318)
						)
					)
					(width 0)
					(fill yes)
				)
			)
		)
	)
	(footprint ""
		(layer "B.Cu")
		(at 88.41232 -45.6692 -90)
		(property "Reference" "SR605"
			(at 0 0 90)
			(layer "B.SilkS")
			(hide yes)
			(effects
				(font
					(size 1.27 1.27)
				)
				(justify mirror)
			)
		)
		(property "Value" "10KR2F-2-GP"
			(at -0.064008 -3.993896 270)
			(unlocked yes)
			(layer "B.Fab")
			(hide yes)
			(effects
				(font
					(size 1.016 1.016)
					(thickness 0.1524)
				)
				(justify mirror)
			)
		)
		(property "Device Type" "R402H16"
			(at -0.064008 -5.517896 270)
			(unlocked yes)
			(layer "B.Fab")
			(hide yes)
			(effects
				(font
					(size 1.016 1.016)
					(thickness 0.1524)
				)
				(justify mirror)
			)
		)
		(duplicate_pad_numbers_are_jumpers no)
		(fp_line
			(start -0.508 -0.9398)
			(end 0.508 -0.9398)
			(stroke
				(width 0.1524)
				(type default)
			)
			(layer "B.SilkS")
		)
		(fp_line
			(start 0.508 -0.9398)
			(end 0.508 0.9398)
			(stroke
				(width 0.1524)
				(type default)
			)
			(layer "B.SilkS")
		)
		(fp_rect
			(start 0.508 0.9398)
			(end -0.508 -0.9398)
			(stroke
				(width 0)
				(type default)
			)
			(fill no)
			(layer "B.CrtYd")
		)
		(fp_rect
			(start 0.508 0.9398)
			(end -0.508 -0.9398)
			(stroke
				(width 0)
				(type default)
			)
			(fill no)
			(layer "B.Fab")
		)
		(pad "1" smd custom
			(at 0 -0.4445 90)
			(size 0.1397 0.1397)
			(layers "B.Cu" "B.Mask" "B.Paste")
			(net "IOC_SIO_BLINK")
			(options
				(clearance outline)
				(anchor circle)
			)
			(primitives
				(gr_poly
					(pts
						(arc
							(start -0.1778 0.2794)
							(mid -0.249642 0.249642)
							(end -0.2794 0.1778)
						)
						(arc
							(start -0.2794 -0.1778)
							(mid -0.249642 -0.249642)
							(end -0.1778 -0.2794)
						)
						(arc
							(start 0.1778 -0.2794)
							(mid 0.249642 -0.249642)
							(end 0.2794 -0.1778)
						)
						(arc
							(start 0.2794 0.1778)
							(mid 0.249642 0.249642)
							(end 0.1778 0.2794)
						)
					)
					(width 0)
					(fill yes)
				)
			)
		)
		(pad "2" smd custom
			(at 0 0.4445 90)
			(size 0.1397 0.1397)
			(layers "B.Cu" "B.Mask" "B.Paste")
			(net "GND")
			(options
				(clearance outline)
				(anchor circle)
			)
			(primitives
				(gr_poly
					(pts
						(arc
							(start -0.1778 0.2794)
							(mid -0.249642 0.249642)
							(end -0.2794 0.1778)
						)
						(arc
							(start -0.2794 -0.1778)
							(mid -0.249642 -0.249642)
							(end -0.1778 -0.2794)
						)
						(arc
							(start 0.1778 -0.2794)
							(mid 0.249642 -0.249642)
							(end 0.2794 -0.1778)
						)
						(arc
							(start 0.2794 0.1778)
							(mid 0.249642 0.249642)
							(end 0.1778 0.2794)
						)
					)
					(width 0)
					(fill yes)
				)
			)
		)
	)
	(footprint ""
		(layer "B.Cu")
		(at 130.283966 -38.354 -90)
		(property "Reference" "SR651"
			(at 0 0 90)
			(layer "B.SilkS")
			(hide yes)
			(effects
				(font
					(size 1.27 1.27)
				)
				(justify mirror)
			)
		)
		(property "Value" "150R2F-1-GP"
			(at -0.064008 -3.993896 270)
			(unlocked yes)
			(layer "B.Fab")
			(hide yes)
			(effects
				(font
					(size 1.016 1.016)
					(thickness 0.1524)
				)
				(justify mirror)
			)
		)
		(property "Device Type" "R402H16"
			(at -0.064008 -5.517896 270)
			(unlocked yes)
			(layer "B.Fab")
			(hide yes)
			(effects
				(font
					(size 1.016 1.016)
					(thickness 0.1524)
				)
				(justify mirror)
			)
		)
		(duplicate_pad_numbers_are_jumpers no)
		(fp_line
			(start -0.508 -0.9398)
			(end 0.508 -0.9398)
			(stroke
				(width 0.1524)
				(type default)
			)
			(layer "B.SilkS")
		)
		(fp_line
			(start 0.508 -0.9398)
			(end 0.508 0.9398)
			(stroke
				(width 0.1524)
				(type default)
			)
			(layer "B.SilkS")
		)
		(fp_rect
			(start 0.508 0.9398)
			(end -0.508 -0.9398)
			(stroke
				(width 0)
				(type default)
			)
			(fill no)
			(layer "B.CrtYd")
		)
		(fp_rect
			(start 0.508 0.9398)
			(end -0.508 -0.9398)
			(stroke
				(width 0)
				(type default)
			)
			(fill no)
			(layer "B.Fab")
		)
		(pad "1" smd custom
			(at 0 -0.4445 90)
			(size 0.1397 0.1397)
			(layers "B.Cu" "B.Mask" "B.Paste")
			(net "P3V3")
			(options
				(clearance outline)
				(anchor circle)
			)
			(primitives
				(gr_poly
					(pts
						(arc
							(start -0.1778 0.2794)
							(mid -0.249642 0.249642)
							(end -0.2794 0.1778)
						)
						(arc
							(start -0.2794 -0.1778)
							(mid -0.249642 -0.249642)
							(end -0.1778 -0.2794)
						)
						(arc
							(start 0.1778 -0.2794)
							(mid 0.249642 -0.249642)
							(end 0.2794 -0.1778)
						)
						(arc
							(start 0.2794 0.1778)
							(mid 0.249642 0.249642)
							(end 0.1778 0.2794)
						)
					)
					(width 0)
					(fill yes)
				)
			)
		)
		(pad "2" smd custom
			(at 0 0.4445 90)
			(size 0.1397 0.1397)
			(layers "B.Cu" "B.Mask" "B.Paste")
			(net "SYS_HB_LED_R")
			(options
				(clearance outline)
				(anchor circle)
			)
			(primitives
				(gr_poly
					(pts
						(arc
							(start -0.1778 0.2794)
							(mid -0.249642 0.249642)
							(end -0.2794 0.1778)
						)
						(arc
							(start -0.2794 -0.1778)
							(mid -0.249642 -0.249642)
							(end -0.1778 -0.2794)
						)
						(arc
							(start 0.1778 -0.2794)
							(mid 0.249642 -0.249642)
							(end 0.2794 -0.1778)
						)
						(arc
							(start 0.2794 0.1778)
							(mid 0.249642 0.249642)
							(end 0.1778 0.2794)
						)
					)
					(width 0)
					(fill yes)
				)
			)
		)
	)
	(footprint ""
		(layer "B.Cu")
		(at 113.044986 -32.46882)
		(property "Reference" "STP93"
			(at 0 0 0)
			(layer "B.SilkS")
			(hide yes)
			(effects
				(font
					(size 1.27 1.27)
				)
				(justify mirror)
			)
		)
		(property "Value" "TPAD28"
			(at -0.0127 -1.8034 0)
			(unlocked yes)
			(layer "B.Fab")
			(hide yes)
			(effects
				(font
					(size 1.016 1.016)
					(thickness 0.1524)
				)
				(justify mirror)
			)
		)
		(property "Device Type" "TPAD28"
			(at -0.0127 -3.3274 0)
			(unlocked yes)
			(layer "B.Fab")
			(hide yes)
			(effects
				(font
					(size 1.016 1.016)
					(thickness 0.1524)
				)
				(justify mirror)
			)
		)
		(duplicate_pad_numbers_are_jumpers no)
		(fp_poly
			(pts
				(arc
					(start 0.3556 0)
					(mid -0.3556 0)
					(end 0.3556 0)
				)
			)
			(stroke
				(width 0)
				(type default)
			)
			(fill no)
			(layer "B.CrtYd")
		)
		(fp_poly
			(pts
				(arc
					(start 0.6096 0)
					(mid -0.6096 0)
					(end 0.6096 0)
				)
			)
			(stroke
				(width 0)
				(type default)
			)
			(fill no)
			(layer "B.Fab")
		)
		(pad "1" smd circle
			(at 0 0 180)
			(size 0.7112 0.7112)
			(layers "B.Cu" "B.Mask" "B.Paste")
			(net "IOC_GPIO_9")
		)
	)
	(footprint ""
		(layer "B.Cu")
		(at 114.281966 -46.863 -90)
		(property "Reference" "SR622"
			(at 0 0 90)
			(layer "B.SilkS")
			(hide yes)
			(effects
				(font
					(size 1.27 1.27)
				)
				(justify mirror)
			)
		)
		(property "Value" "2K2R2F-GP"
			(at -0.064008 -3.993896 270)
			(unlocked yes)
			(layer "B.Fab")
			(hide yes)
			(effects
				(font
					(size 1.016 1.016)
					(thickness 0.1524)
				)
				(justify mirror)
			)
		)
		(property "Device Type" "R402H16"
			(at -0.064008 -5.517896 270)
			(unlocked yes)
			(layer "B.Fab")
			(hide yes)
			(effects
				(font
					(size 1.016 1.016)
					(thickness 0.1524)
				)
				(justify mirror)
			)
		)
		(duplicate_pad_numbers_are_jumpers no)
		(fp_line
			(start -0.508 -0.9398)
			(end 0.508 -0.9398)
			(stroke
				(width 0.1524)
				(type default)
			)
			(layer "B.SilkS")
		)
		(fp_line
			(start 0.508 -0.9398)
			(end 0.508 0.9398)
			(stroke
				(width 0.1524)
				(type default)
			)
			(layer "B.SilkS")
		)
		(fp_rect
			(start 0.508 0.9398)
			(end -0.508 -0.9398)
			(stroke
				(width 0)
				(type default)
			)
			(fill no)
			(layer "B.CrtYd")
		)
		(fp_rect
			(start 0.508 0.9398)
			(end -0.508 -0.9398)
			(stroke
				(width 0)
				(type default)
			)
			(fill no)
			(layer "B.Fab")
		)
		(pad "1" smd custom
			(at 0 -0.4445 90)
			(size 0.1397 0.1397)
			(layers "B.Cu" "B.Mask" "B.Paste")
			(net "P1V8_C")
			(options
				(clearance outline)
				(anchor circle)
			)
			(primitives
				(gr_poly
					(pts
						(arc
							(start -0.1778 0.2794)
							(mid -0.249642 0.249642)
							(end -0.2794 0.1778)
						)
						(arc
							(start -0.2794 -0.1778)
							(mid -0.249642 -0.249642)
							(end -0.1778 -0.2794)
						)
						(arc
							(start 0.1778 -0.2794)
							(mid 0.249642 -0.249642)
							(end 0.2794 -0.1778)
						)
						(arc
							(start 0.2794 0.1778)
							(mid 0.249642 0.249642)
							(end 0.1778 0.2794)
						)
					)
					(width 0)
					(fill yes)
				)
			)
		)
		(pad "2" smd custom
			(at 0 0.4445 90)
			(size 0.1397 0.1397)
			(layers "B.Cu" "B.Mask" "B.Paste")
			(net "IOC_SCL_3")
			(options
				(clearance outline)
				(anchor circle)
			)
			(primitives
				(gr_poly
					(pts
						(arc
							(start -0.1778 0.2794)
							(mid -0.249642 0.249642)
							(end -0.2794 0.1778)
						)
						(arc
							(start -0.2794 -0.1778)
							(mid -0.249642 -0.249642)
							(end -0.1778 -0.2794)
						)
						(arc
							(start 0.1778 -0.2794)
							(mid 0.249642 -0.249642)
							(end 0.2794 -0.1778)
						)
						(arc
							(start 0.2794 0.1778)
							(mid 0.249642 0.249642)
							(end 0.1778 0.2794)
						)
					)
					(width 0)
					(fill yes)
				)
			)
		)
	)
	(footprint ""
		(layer "B.Cu")
		(at 119.0244 -34.7218)
		(property "Reference" "STP142"
			(at 0 0 0)
			(layer "B.SilkS")
			(hide yes)
			(effects
				(font
					(size 1.27 1.27)
				)
				(justify mirror)
			)
		)
		(property "Value" "TPAD28"
			(at -0.0127 -1.8034 0)
			(unlocked yes)
			(layer "B.Fab")
			(hide yes)
			(effects
				(font
					(size 1.016 1.016)
					(thickness 0.1524)
				)
				(justify mirror)
			)
		)
		(property "Device Type" "TPAD28"
			(at -0.0127 -3.3274 0)
			(unlocked yes)
			(layer "B.Fab")
			(hide yes)
			(effects
				(font
					(size 1.016 1.016)
					(thickness 0.1524)
				)
				(justify mirror)
			)
		)
		(duplicate_pad_numbers_are_jumpers no)
		(fp_poly
			(pts
				(arc
					(start 0.3556 0)
					(mid -0.3556 0)
					(end 0.3556 0)
				)
			)
			(stroke
				(width 0)
				(type default)
			)
			(fill no)
			(layer "B.CrtYd")
		)
		(fp_poly
			(pts
				(arc
					(start 0.6096 0)
					(mid -0.6096 0)
					(end 0.6096 0)
				)
			)
			(stroke
				(width 0)
				(type default)
			)
			(fill no)
			(layer "B.Fab")
		)
		(pad "1" smd circle
			(at 0 0 180)
			(size 0.7112 0.7112)
			(layers "B.Cu" "B.Mask" "B.Paste")
			(net "IOC_GPIO_23")
		)
	)
	(footprint ""
		(layer "B.Cu")
		(at 98.806 -48.26 -90)
		(property "Reference" "SC1044"
			(at 0 0 90)
			(layer "B.SilkS")
			(hide yes)
			(effects
				(font
					(size 1.27 1.27)
				)
				(justify mirror)
			)
		)
		(property "Value" "SCD1U16V2KX-3GP"
			(at -1.1811 -2.7051 270)
			(unlocked yes)
			(layer "B.Fab")
			(hide yes)
			(effects
				(font
					(size 1.016 1.016)
					(thickness 0.1524)
				)
				(justify mirror)
			)
		)
		(property "Device Type" "C402H22"
			(at -1.1811 -4.2291 270)
			(unlocked yes)
			(layer "B.Fab")
			(hide yes)
			(effects
				(font
					(size 1.016 1.016)
					(thickness 0.1524)
				)
				(justify mirror)
			)
		)
		(duplicate_pad_numbers_are_jumpers no)
		(fp_rect
			(start 0.4318 0.9525)
			(end -0.4318 -0.9525)
			(stroke
				(width 0)
				(type default)
			)
			(fill no)
			(layer "B.CrtYd")
		)
		(fp_rect
			(start 0.4318 0.9525)
			(end -0.4318 -0.9525)
			(stroke
				(width 0)
				(type default)
			)
			(fill no)
			(layer "B.Fab")
		)
		(pad "1" smd custom
			(at 0 -0.4445 90)
			(size 0.1524 0.1524)
			(layers "B.Cu" "B.Mask" "B.Paste")
			(net "P0V955_C")
			(options
				(clearance outline)
				(anchor circle)
			)
			(primitives
				(gr_poly
					(pts
						(arc
							(start 0.3048 0.2032)
							(mid 0.275042 0.275042)
							(end 0.2032 0.3048)
						)
						(arc
							(start -0.2032 0.3048)
							(mid -0.275042 0.275042)
							(end -0.3048 0.2032)
						)
						(arc
							(start -0.3048 -0.2032)
							(mid -0.275042 -0.275042)
							(end -0.2032 -0.3048)
						)
						(arc
							(start 0.2032 -0.3048)
							(mid 0.275042 -0.275042)
							(end 0.3048 -0.2032)
						)
					)
					(width 0)
					(fill yes)
				)
			)
		)
		(pad "2" smd custom
			(at 0 0.4445 90)
			(size 0.1524 0.1524)
			(layers "B.Cu" "B.Mask" "B.Paste")
			(net "GND")
			(options
				(clearance outline)
				(anchor circle)
			)
			(primitives
				(gr_poly
					(pts
						(arc
							(start 0.3048 0.2032)
							(mid 0.275042 0.275042)
							(end 0.2032 0.3048)
						)
						(arc
							(start -0.2032 0.3048)
							(mid -0.275042 0.275042)
							(end -0.3048 0.2032)
						)
						(arc
							(start -0.3048 -0.2032)
							(mid -0.275042 -0.275042)
							(end -0.2032 -0.3048)
						)
						(arc
							(start 0.2032 -0.3048)
							(mid 0.275042 -0.275042)
							(end 0.3048 -0.2032)
						)
					)
					(width 0)
					(fill yes)
				)
			)
		)
	)
	(footprint ""
		(layer "B.Cu")
		(at 114.281966 -44.577 90)
		(property "Reference" "SR584"
			(at 0 0 90)
			(layer "B.SilkS")
			(hide yes)
			(effects
				(font
					(size 1.27 1.27)
				)
				(justify mirror)
			)
		)
		(property "Value" "10KR2F-2-GP"
			(at -0.064008 -3.993896 90)
			(unlocked yes)
			(layer "B.Fab")
			(hide yes)
			(effects
				(font
					(size 1.016 1.016)
					(thickness 0.1524)
				)
				(justify mirror)
			)
		)
		(property "Device Type" "R402H16"
			(at -0.064008 -5.517896 90)
			(unlocked yes)
			(layer "B.Fab")
			(hide yes)
			(effects
				(font
					(size 1.016 1.016)
					(thickness 0.1524)
				)
				(justify mirror)
			)
		)
		(duplicate_pad_numbers_are_jumpers no)
		(fp_line
			(start 0.508 -0.9398)
			(end 0.508 0.9398)
			(stroke
				(width 0.1524)
				(type default)
			)
			(layer "B.SilkS")
		)
		(fp_line
			(start -0.508 -0.9398)
			(end 0.508 -0.9398)
			(stroke
				(width 0.1524)
				(type default)
			)
			(layer "B.SilkS")
		)
		(fp_rect
			(start 0.508 0.9398)
			(end -0.508 -0.9398)
			(stroke
				(width 0)
				(type default)
			)
			(fill no)
			(layer "B.CrtYd")
		)
		(fp_rect
			(start 0.508 0.9398)
			(end -0.508 -0.9398)
			(stroke
				(width 0)
				(type default)
			)
			(fill no)
			(layer "B.Fab")
		)
		(pad "1" smd custom
			(at 0 -0.4445 270)
			(size 0.1397 0.1397)
			(layers "B.Cu" "B.Mask" "B.Paste")
			(net "IOC_CLK_SEL1")
			(options
				(clearance outline)
				(anchor circle)
			)
			(primitives
				(gr_poly
					(pts
						(arc
							(start -0.1778 0.2794)
							(mid -0.249642 0.249642)
							(end -0.2794 0.1778)
						)
						(arc
							(start -0.2794 -0.1778)
							(mid -0.249642 -0.249642)
							(end -0.1778 -0.2794)
						)
						(arc
							(start 0.1778 -0.2794)
							(mid 0.249642 -0.249642)
							(end 0.2794 -0.1778)
						)
						(arc
							(start 0.2794 0.1778)
							(mid 0.249642 0.249642)
							(end 0.1778 0.2794)
						)
					)
					(width 0)
					(fill yes)
				)
			)
		)
		(pad "2" smd custom
			(at 0 0.4445 270)
			(size 0.1397 0.1397)
			(layers "B.Cu" "B.Mask" "B.Paste")
			(net "P1V8_C")
			(options
				(clearance outline)
				(anchor circle)
			)
			(primitives
				(gr_poly
					(pts
						(arc
							(start -0.1778 0.2794)
							(mid -0.249642 0.249642)
							(end -0.2794 0.1778)
						)
						(arc
							(start -0.2794 -0.1778)
							(mid -0.249642 -0.249642)
							(end -0.1778 -0.2794)
						)
						(arc
							(start 0.1778 -0.2794)
							(mid 0.249642 -0.249642)
							(end 0.2794 -0.1778)
						)
						(arc
							(start 0.2794 0.1778)
							(mid 0.249642 0.249642)
							(end 0.1778 0.2794)
						)
					)
					(width 0)
					(fill yes)
				)
			)
		)
	)
	(footprint ""
		(layer "B.Cu")
		(at 109.86897 -84.709)
		(property "Reference" "STP101"
			(at 0 0 0)
			(layer "B.SilkS")
			(hide yes)
			(effects
				(font
					(size 1.27 1.27)
				)
				(justify mirror)
			)
		)
		(property "Value" "TPAD28"
			(at -0.0127 -1.8034 0)
			(unlocked yes)
			(layer "B.Fab")
			(hide yes)
			(effects
				(font
					(size 1.016 1.016)
					(thickness 0.1524)
				)
				(justify mirror)
			)
		)
		(property "Device Type" "TPAD28"
			(at -0.0127 -3.3274 0)
			(unlocked yes)
			(layer "B.Fab")
			(hide yes)
			(effects
				(font
					(size 1.016 1.016)
					(thickness 0.1524)
				)
				(justify mirror)
			)
		)
		(duplicate_pad_numbers_are_jumpers no)
		(fp_poly
			(pts
				(arc
					(start 0.3556 0)
					(mid -0.3556 0)
					(end 0.3556 0)
				)
			)
			(stroke
				(width 0)
				(type default)
			)
			(fill no)
			(layer "B.CrtYd")
		)
		(fp_poly
			(pts
				(arc
					(start 0.6096 0)
					(mid -0.6096 0)
					(end 0.6096 0)
				)
			)
			(stroke
				(width 0)
				(type default)
			)
			(fill no)
			(layer "B.Fab")
		)
		(pad "1" smd circle
			(at 0 0 180)
			(size 0.7112 0.7112)
			(layers "B.Cu" "B.Mask" "B.Paste")
			(net "TESTIBIAS")
		)
	)
)
